# BASEBOARD_FAB2 (Tioga Pass) — schematic netlist excerpt (pin names and nets, part order shuffled) for the footprints in the layout excerpt that follows; sources: Cadence DE-HDL packaged netlist, KiCad conversion of Wiwynn_Tioga_Pass_MB.brd

R2T39  RES  100.0 1% CHIP  pkg 0402  page 93 : A = P0V7_GTL2104_5_VREF ; B = GND
C8B15  CAP  47UF 4V 20% X6S  pkg 0805  page 131 : A = P1V05_PCH_STBY ; B = GND
C25W1  CAP  1.0UF 16V 10% X6S  pkg 0402  page 151 : A = P1V2_AUX_BMC ; B = GND

(kicad_pcb
	(version 20260206)
	(generator "pcbnew")
	(generator_version "10.0")
	(general
		(thickness 1.6)
		(legacy_teardrops no)
	)
	(paper "A4")
	(title_block
		(title "Wiwynn_Tioga_Pass_MB.brd")
		(comment 1 "Tioga Pass / footprints 3111-3113 of 4770")
	)
	(layers
		(0 "F.Cu" signal "TOP")
		(4 "In1.Cu" signal "L2GND")
		(6 "In2.Cu" signal "L3")
		(8 "In3.Cu" signal "L4GND")
		(10 "In4.Cu" signal "L5")
		(12 "In5.Cu" signal "L6GND")
		(14 "In6.Cu" signal "L7VCC")
		(16 "In7.Cu" signal "L8VCC")
		(18 "In8.Cu" signal "L9GND")
		(20 "In9.Cu" signal "L10")
		(22 "In10.Cu" signal "L11GND")
		(24 "In11.Cu" signal "L12")
		(26 "In12.Cu" signal "L13GND")
		(2 "B.Cu" signal "BOTTOM")
		(9 "F.Adhes" user "F.Adhesive")
		(11 "B.Adhes" user "B.Adhesive")
		(13 "F.Paste" user "Package Geometry/Pastemask Top")
		(15 "B.Paste" user "Package Geometry/Pastemask Bottom")
		(5 "F.SilkS" user "Ref Des/Silkscreen Top")
		(7 "B.SilkS" user "Ref Des/Silkscreen Bottom")
		(1 "F.Mask" user "Board Geometry/Soldermask Top")
		(3 "B.Mask" user "Board Geometry/Soldermask Bottom")
		(17 "Dwgs.User" user "User.Drawings")
		(19 "Cmts.User" user "User.Comments")
		(21 "Eco1.User" user "User.Eco1")
		(23 "Eco2.User" user "User.Eco2")
		(25 "Edge.Cuts" user "Board Geometry/Outline")
		(27 "Margin" user)
		(31 "F.CrtYd" user "Package Geometry/Place Bound Top")
		(29 "B.CrtYd" user "Package Geometry/Place Bound Bottom")
		(35 "F.Fab" user "Ref Des/Assembly Top")
		(33 "B.Fab" user "Ref Des/Assembly Bottom")
	)
	(footprint ""
		(layer "B.Cu")
		(at 445.02324 -24.28494)
		(property "Reference" "C25W1"
			(at 0.8382 -0.67818 0)
			(unlocked yes)
			(layer "B.SilkS")
			(effects
				(font
					(size 0.4064 0.254)
					(thickness 0.1524)
				)
				(justify left mirror)
			)
		)
		(property "Value" ""
			(at 0 0 0)
			(layer "B.Fab")
			(effects
				(font
					(size 1.27 1.27)
				)
				(justify mirror)
			)
		)
		(duplicate_pad_numbers_are_jumpers no)
		(fp_poly
			(pts
				(xy -0.3048 -0.1016) (xy -0.3048 0.9906) (xy 0.3048 0.9906) (xy 0.3048 -0.1016)
			)
			(stroke
				(width 0)
				(type default)
			)
			(fill no)
			(layer "B.CrtYd")
		)
		(fp_line
			(start -0.3048 -0.1016)
			(end 0.3048 -0.1016)
			(stroke
				(width 0.1)
				(type default)
			)
			(layer "B.Fab")
		)
		(fp_line
			(start -0.3048 0.9906)
			(end -0.3048 -0.1016)
			(stroke
				(width 0.1)
				(type default)
			)
			(layer "B.Fab")
		)
		(fp_line
			(start 0.3048 -0.1016)
			(end 0.3048 0.9906)
			(stroke
				(width 0.1)
				(type default)
			)
			(layer "B.Fab")
		)
		(fp_line
			(start 0.3048 0.9906)
			(end -0.3048 0.9906)
			(stroke
				(width 0.1)
				(type default)
			)
			(layer "B.Fab")
		)
		(pad "1" smd rect
			(at 0 0 180)
			(size 0.508 0.508)
			(layers "B.Cu" "B.Mask" "B.Paste")
			(net "P1V2_AUX_BMC")
		)
		(pad "2" smd rect
			(at 0 0.889 180)
			(size 0.508 0.508)
			(layers "B.Cu" "B.Mask" "B.Paste")
			(net "GND")
		)
		(zone
			(layer "B.Cu")
			(hatch none 0.5)
			(connect_pads
				(clearance 0)
			)
			(min_thickness 0.25)
			(keepout
				(tracks allowed)
				(vias not_allowed)
				(pads allowed)
				(copperpour not_allowed)
				(footprints allowed)
			)
			(placement
				(enabled no)
				(sheetname "")
			)
			(fill
				(thermal_gap 0.5)
				(thermal_bridge_width 0.5)
				(island_removal_mode 0)
			)
			(polygon
				(pts
					(xy 445.27724 -24.03094) (xy 444.76924 -24.03094) (xy 444.76924 -23.64994) (xy 445.27724 -23.64994)
				)
			)
		)
		(zone
			(layer "B.Cu")
			(hatch none 0.5)
			(connect_pads
				(clearance 0)
			)
			(min_thickness 0.25)
			(keepout
				(tracks not_allowed)
				(vias allowed)
				(pads allowed)
				(copperpour not_allowed)
				(footprints allowed)
			)
			(placement
				(enabled no)
				(sheetname "")
			)
			(fill
				(thermal_gap 0.5)
				(thermal_bridge_width 0.5)
				(island_removal_mode 0)
			)
			(polygon
				(pts
					(xy 445.27724 -23.64994) (xy 444.76924 -23.64994) (xy 444.76924 -24.03094) (xy 445.27724 -24.03094)
				)
			)
		)
	)
	(footprint ""
		(layer "B.Cu")
		(at 413.639 -121.92 180)
		(property "Reference" "C8B15"
			(at 0 0 0)
			(layer "B.SilkS")
			(hide yes)
			(effects
				(font
					(size 1.27 1.27)
				)
				(justify mirror)
			)
		)
		(property "Value" ""
			(at 0 0 0)
			(layer "B.Fab")
			(effects
				(font
					(size 1.27 1.27)
				)
				(justify mirror)
			)
		)
		(duplicate_pad_numbers_are_jumpers no)
		(fp_poly
			(pts
				(xy 0.7239 -0.2159) (xy -0.7239 -0.2159) (xy -0.7239 1.9939) (xy 0.7239 1.9939)
			)
			(stroke
				(width 0)
				(type default)
			)
			(fill no)
			(layer "B.CrtYd")
		)
		(fp_line
			(start 0.7239 1.9939)
			(end -0.7239 1.9939)
			(stroke
				(width 0.1)
				(type default)
			)
			(layer "B.Fab")
		)
		(fp_line
			(start 0.7239 -0.2159)
			(end 0.7239 1.9939)
			(stroke
				(width 0.1)
				(type default)
			)
			(layer "B.Fab")
		)
		(fp_line
			(start -0.7239 1.9939)
			(end -0.7239 -0.2159)
			(stroke
				(width 0.1)
				(type default)
			)
			(layer "B.Fab")
		)
		(fp_line
			(start -0.7239 -0.2159)
			(end 0.7239 -0.2159)
			(stroke
				(width 0.1)
				(type default)
			)
			(layer "B.Fab")
		)
		(pad "1" smd rect
			(at 0 0)
			(size 1.27 1.016)
			(layers "B.Cu" "B.Mask" "B.Paste")
			(net "P1V05_PCH_STBY")
		)
		(pad "2" smd rect
			(at 0 1.778)
			(size 1.27 1.016)
			(layers "B.Cu" "B.Mask" "B.Paste")
			(net "GND")
		)
		(zone
			(layer "B.Cu")
			(hatch none 0.5)
			(connect_pads
				(clearance 0)
			)
			(min_thickness 0.25)
			(keepout
				(tracks not_allowed)
				(vias allowed)
				(pads allowed)
				(copperpour not_allowed)
				(footprints allowed)
			)
			(placement
				(enabled no)
				(sheetname "")
			)
			(fill
				(thermal_gap 0.5)
				(thermal_bridge_width 0.5)
				(island_removal_mode 0)
			)
			(polygon
				(pts
					(xy 413.004 -122.428) (xy 414.274 -122.428) (xy 414.274 -123.19) (xy 413.004 -123.19)
				)
			)
		)
	)
	(footprint ""
		(layer "B.Cu")
		(at 375.0945 -45.72 90)
		(property "Reference" "R2T39"
			(at 0 0 90)
			(layer "B.SilkS")
			(hide yes)
			(effects
				(font
					(size 1.27 1.27)
				)
				(justify mirror)
			)
		)
		(property "Value" ""
			(at 0 0 90)
			(layer "B.Fab")
			(effects
				(font
					(size 1.27 1.27)
				)
				(justify mirror)
			)
		)
		(duplicate_pad_numbers_are_jumpers no)
		(fp_poly
			(pts
				(xy 0.2794 -0.1016) (xy -0.2794 -0.1016) (xy -0.2794 0.9906) (xy 0.2794 0.9906)
			)
			(stroke
				(width 0)
				(type default)
			)
			(fill no)
			(layer "B.CrtYd")
		)
		(fp_line
			(start 0.2794 -0.1016)
			(end 0.2794 0.9906)
			(stroke
				(width 0.1)
				(type default)
			)
			(layer "B.Fab")
		)
		(fp_line
			(start -0.2794 -0.1016)
			(end 0.2794 -0.1016)
			(stroke
				(width 0.1)
				(type default)
			)
			(layer "B.Fab")
		)
		(fp_line
			(start 0.2794 0.9906)
			(end -0.2794 0.9906)
			(stroke
				(width 0.1)
				(type default)
			)
			(layer "B.Fab")
		)
		(fp_line
			(start -0.2794 0.9906)
			(end -0.2794 -0.1016)
			(stroke
				(width 0.1)
				(type default)
			)
			(layer "B.Fab")
		)
		(pad "1" smd rect
			(at 0 0 270)
			(size 0.508 0.508)
			(layers "B.Cu" "B.Mask" "B.Paste")
			(net "P0V7_GTL2104_5_VREF")
		)
		(pad "2" smd rect
			(at 0 0.889 270)
			(size 0.508 0.508)
			(layers "B.Cu" "B.Mask" "B.Paste")
			(net "GND")
		)
		(zone
			(layer "B.Cu")
			(hatch none 0.5)
			(connect_pads
				(clearance 0)
			)
			(min_thickness 0.25)
			(keepout
				(tracks allowed)
				(vias not_allowed)
				(pads allowed)
				(copperpour not_allowed)
				(footprints allowed)
			)
			(placement
				(enabled no)
				(sheetname "")
			)
			(fill
				(thermal_gap 0.5)
				(thermal_bridge_width 0.5)
				(island_removal_mode 0)
			)
			(polygon
				(pts
					(xy 375.3485 -45.974) (xy 375.3485 -45.466) (xy 375.7295 -45.466) (xy 375.7295 -45.974)
				)
			)
		)
		(zone
			(layer "B.Cu")
			(hatch none 0.5)
			(connect_pads
				(clearance 0)
			)
			(min_thickness 0.25)
			(keepout
				(tracks not_allowed)
				(vias allowed)
				(pads allowed)
				(copperpour not_allowed)
				(footprints allowed)
			)
			(placement
				(enabled no)
				(sheetname "")
			)
			(fill
				(thermal_gap 0.5)
				(thermal_bridge_width 0.5)
				(island_removal_mode 0)
			)
			(polygon
				(pts
					(xy 375.7295 -45.974) (xy 375.7295 -45.466) (xy 375.3485 -45.466) (xy 375.3485 -45.974)
				)
			)
		)
	)
)
